# BASEBOARD_FAB2 (Tioga Pass) — schematic netlist excerpt (pin names and nets, part order shuffled) for the footprints in the layout excerpt that follows; sources: Cadence DE-HDL packaged netlist, KiCad conversion of Wiwynn_Tioga_Pass_MB.brd

J6B1  SCONN120_H61426002  CONN  pkg SM  page 194
  IOA1  = P12V_STBY
  IOA2  = P12V_STBY
  IOA3  = P12V_STBY
  IOA4  = P12V_STBY
  IOA5  = P12V_STBY
  IOA6  = P12V_STBY
  IOA7  = P12V_STBY
  IOA8  = P12V_STBY
  IOA9  = GND
  IOA10  = GND
  IOA11  = P3V3_STBY
  IOA12  = GND
  IOA13  = P5V_STBY
  IOA14  = GND
  IOA15  = FM_P1V8MCP_CPU0_EN
  IOA16  = FM_PVCCIOMCP_CPU0_EN
  IOA17  = GND
  IOA18  = SMB_VR_STBY_LVC3_SCL
  IOA19  = SVID_ALERT0_CPU0_R_N
  IOA20  = SVID_CLK0_CPU0_R
  IOB1  = P12V_STBY
  IOB2  = P12V_STBY
  IOB3  = P12V_STBY
  IOB4  = P12V_STBY
  IOB5  = P12V_STBY
  IOB6  = P12V_STBY
  IOB7  = P12V_STBY
  IOB8  = P12V_STBY
  IOB9  = GND
  IOB10  = GND
  IOB11  = P3V3_STBY
  IOB12  = GND
  IOB13  = P5V_STBY
  IOB14  = GND
  IOB15  = PWRGD_P1V8MCP_CPU0
  IOB16  = PWRGD_PVCCIOMCP_CPU0
  IOB17  = GND
  IOB18  = SMB_VR_STBY_LVC3_SDA
  IOB19  = SVID_ALERT1_CPU0_R_N
  IOB20  = SVID_DIO0_CPU0_R
  IOC1  = GND
  IOC2  = GND
  IOC3  = GND
  IOC4  = GND
  IOC5  = GND
  IOC6  = GND
  IOC7  = GND
  IOC8  = GND
  IOC9  = GND
  IOC10  = GND
  IOC11  = P3V3_STBY
  IOC12  = GND
  IOC13  = P5V_STBY
  IOC14  = GND
  IOC15  = GND
  IOC16  = GND
  IOC17  = PVCCIOMCP_CPU0
  IOC18  = PVCCIOMCP_CPU0
  IOC19  = PVCCIOMCP_CPU0
  IOC20  = FM_PVCCMCP_CPU0_EN
  IOD1  = P3V3
  IOD2  = GND
  IOD3  = GND
  IOD4  = GND
  IOD5  = GND
  IOD6  = GND
  IOD7  = GND
  IOD8  = GND
  IOD9  = GND
  IOD10  = GND
  IOD11  = GND
  IOD12  = GND
  IOD13  = GND
  IOD14  = GND
  IOD15  = GND
  IOD16  = GND
  IOD17  = PVCCIOMCP_CPU0
  IOD18  = PVCCIOMCP_CPU0
  IOD19  = PVCCIOMCP_CPU0
  IOD20  = PWRGD_PVCCMCP_CPU0
  IOE1  = FM_CPU0_VRM_322M_156M_OSC_EN
  IOE2  = GND
  IOE3  = GND
  IOE4  = GND
  IOE5  = GND
  IOE6  = GND
  IOE7  = GND
  IOE8  = VSENSE_PVCCIOMCP_CPU0_SKT_VSEN
  IOE9  = GND
  IOE10  = VR_PVCCIOMCP_CPU0_XADDR1
  IOE11  = GND
  IOE12  = GND
  IOE13  = GND
  IOE14  = GND
  IOE15  = PVCCIOMCP_CPU0
  IOE16  = PVCCIOMCP_CPU0
  IOE17  = PVCCIOMCP_CPU0
  IOE18  = PVCCIOMCP_CPU0
  IOE19  = PVCCIOMCP_CPU0
  IOE20  = SVID_CLK1_CPU0_R
  IOF1  = PVCCIO_CPU0
  IOF2  = GND
  IOF3  = GND
  IOF4  = GND
  IOF5  = GND
  IOF6  = GND
  IOF7  = GND
  IOF8  = VSENSE_PVCCIOMCP_CPU0_SKT_VRTN
  IOF9  = GND
  IOF10  = VR_PVCCMCP_CPU0_XADDR2
  IOF11  = GND
  IOF12  = GND
  IOF13  = GND
  IOF14  = GND
  IOF15  = PVCCIOMCP_CPU0
  IOF16  = PVCCIOMCP_CPU0
  IOF17  = PVCCIOMCP_CPU0
  IOF18  = PVCCIOMCP_CPU0
  IOF19  = PVCCIOMCP_CPU0
  IOF20  = SVID_DIO1_CPU0_R

(kicad_pcb
	(version 20260206)
	(generator "pcbnew")
	(generator_version "10.0")
	(general
		(thickness 1.6)
		(legacy_teardrops no)
	)
	(paper "A4")
	(title_block
		(title "Wiwynn_Tioga_Pass_MB.brd")
		(comment 1 "Tioga Pass / footprint 1366 of 4770 (J6B1), pads 1-51 of 122")
	)
	(layers
		(0 "F.Cu" signal "TOP")
		(4 "In1.Cu" signal "L2GND")
		(6 "In2.Cu" signal "L3")
		(8 "In3.Cu" signal "L4GND")
		(10 "In4.Cu" signal "L5")
		(12 "In5.Cu" signal "L6GND")
		(14 "In6.Cu" signal "L7VCC")
		(16 "In7.Cu" signal "L8VCC")
		(18 "In8.Cu" signal "L9GND")
		(20 "In9.Cu" signal "L10")
		(22 "In10.Cu" signal "L11GND")
		(24 "In11.Cu" signal "L12")
		(26 "In12.Cu" signal "L13GND")
		(2 "B.Cu" signal "BOTTOM")
		(9 "F.Adhes" user "F.Adhesive")
		(11 "B.Adhes" user "B.Adhesive")
		(13 "F.Paste" user "Package Geometry/Pastemask Top")
		(15 "B.Paste" user "Package Geometry/Pastemask Bottom")
		(5 "F.SilkS" user "Ref Des/Silkscreen Top")
		(7 "B.SilkS" user "Ref Des/Silkscreen Bottom")
		(1 "F.Mask" user "Board Geometry/Soldermask Top")
		(3 "B.Mask" user "Board Geometry/Soldermask Bottom")
		(17 "Dwgs.User" user "User.Drawings")
		(19 "Cmts.User" user "User.Comments")
		(21 "Eco1.User" user "User.Eco1")
		(23 "Eco2.User" user "User.Eco2")
		(25 "Edge.Cuts" user "Board Geometry/Outline")
		(27 "Margin" user)
		(31 "F.CrtYd" user "Package Geometry/Place Bound Top")
		(29 "B.CrtYd" user "Package Geometry/Place Bound Bottom")
		(35 "F.Fab" user "Ref Des/Assembly Top")
		(33 "B.Fab" user "Ref Des/Assembly Bottom")
	)
	(footprint ""
		(layer "F.Cu")
		(at 329.594972 -115.55095 90)
		(property "Reference" "J6B1"
			(at -3.59283 -5.018024 90)
			(unlocked yes)
			(layer "F.SilkS")
			(effects
				(font
					(size 0.7874 0.5842)
					(thickness 0.1524)
				)
			)
		)
		(property "Value" ""
			(at 0 0 90)
			(layer "F.Fab")
			(effects
				(font
					(size 1.27 1.27)
				)
			)
		)
		(duplicate_pad_numbers_are_jumpers no)
		(pad "" np_thru_hole circle
			(at -3.175 26.5557 90)
			(size 0.254 0.254)
			(drill 1.27)
			(layers "*.Cu" "*.Mask")
			(clearance 0.8255)
			(thermal_gap 0.8255)
		)
		(pad "" np_thru_hole circle
			(at -0.127 -2.4257 90)
			(size 0.254 0.254)
			(drill 1.27)
			(layers "*.Cu" "*.Mask")
			(clearance 0.8255)
			(thermal_gap 0.8255)
		)
		(pad "A1" smd circle
			(at 0 0 90)
			(size 0.635 0.635)
			(layers "F.Cu" "F.Mask" "F.Paste")
			(net "P12V_STBY")
		)
		(pad "A2" smd circle
			(at 0 1.27 90)
			(size 0.635 0.635)
			(layers "F.Cu" "F.Mask" "F.Paste")
			(net "P12V_STBY")
		)
		(pad "A3" smd circle
			(at 0 2.54 90)
			(size 0.635 0.635)
			(layers "F.Cu" "F.Mask" "F.Paste")
			(net "P12V_STBY")
		)
		(pad "A4" smd circle
			(at 0 3.81 90)
			(size 0.635 0.635)
			(layers "F.Cu" "F.Mask" "F.Paste")
			(net "P12V_STBY")
		)
		(pad "A5" smd circle
			(at 0 5.08 90)
			(size 0.635 0.635)
			(layers "F.Cu" "F.Mask" "F.Paste")
			(net "P12V_STBY")
		)
		(pad "A6" smd circle
			(at 0 6.35 90)
			(size 0.635 0.635)
			(layers "F.Cu" "F.Mask" "F.Paste")
			(net "P12V_STBY")
		)
		(pad "A7" smd circle
			(at 0 7.62 90)
			(size 0.635 0.635)
			(layers "F.Cu" "F.Mask" "F.Paste")
			(net "P12V_STBY")
		)
		(pad "A8" smd circle
			(at 0 8.89 90)
			(size 0.635 0.635)
			(layers "F.Cu" "F.Mask" "F.Paste")
			(net "P12V_STBY")
		)
		(pad "A9" smd circle
			(at 0 10.16 90)
			(size 0.635 0.635)
			(layers "F.Cu" "F.Mask" "F.Paste")
			(net "GND")
		)
		(pad "A10" smd circle
			(at 0 11.43 90)
			(size 0.635 0.635)
			(layers "F.Cu" "F.Mask" "F.Paste")
			(net "GND")
		)
		(pad "A11" smd circle
			(at 0 12.7 90)
			(size 0.635 0.635)
			(layers "F.Cu" "F.Mask" "F.Paste")
			(net "P3V3_STBY")
		)
		(pad "A12" smd circle
			(at 0 13.97 90)
			(size 0.635 0.635)
			(layers "F.Cu" "F.Mask" "F.Paste")
			(net "GND")
		)
		(pad "A13" smd circle
			(at 0 15.24 90)
			(size 0.635 0.635)
			(layers "F.Cu" "F.Mask" "F.Paste")
			(net "P5V_STBY")
		)
		(pad "A14" smd circle
			(at 0 16.51 90)
			(size 0.635 0.635)
			(layers "F.Cu" "F.Mask" "F.Paste")
			(net "GND")
		)
		(pad "A15" smd circle
			(at 0 17.78 90)
			(size 0.635 0.635)
			(layers "F.Cu" "F.Mask" "F.Paste")
			(net "FM_P1V8MCP_CPU0_EN")
		)
		(pad "A16" smd circle
			(at 0 19.05 90)
			(size 0.635 0.635)
			(layers "F.Cu" "F.Mask" "F.Paste")
			(net "FM_PVCCIOMCP_CPU0_EN")
		)
		(pad "A17" smd circle
			(at 0 20.32 90)
			(size 0.635 0.635)
			(layers "F.Cu" "F.Mask" "F.Paste")
			(net "GND")
		)
		(pad "A18" smd circle
			(at 0 21.59 90)
			(size 0.635 0.635)
			(layers "F.Cu" "F.Mask" "F.Paste")
			(net "SMB_VR_STBY_LVC3_SCL")
		)
		(pad "A19" smd circle
			(at 0 22.86 90)
			(size 0.635 0.635)
			(layers "F.Cu" "F.Mask" "F.Paste")
			(net "SVID_ALERT0_CPU0_R_N")
		)
		(pad "A20" smd circle
			(at 0 24.13 90)
			(size 0.635 0.635)
			(layers "F.Cu" "F.Mask" "F.Paste")
			(net "SVID_CLK0_CPU0_R")
		)
		(pad "B1" smd circle
			(at -1.27 0 90)
			(size 0.635 0.635)
			(layers "F.Cu" "F.Mask" "F.Paste")
			(net "P12V_STBY")
		)
		(pad "B2" smd circle
			(at -1.27 1.27 90)
			(size 0.635 0.635)
			(layers "F.Cu" "F.Mask" "F.Paste")
			(net "P12V_STBY")
		)
		(pad "B3" smd circle
			(at -1.27 2.54 90)
			(size 0.635 0.635)
			(layers "F.Cu" "F.Mask" "F.Paste")
			(net "P12V_STBY")
		)
		(pad "B4" smd circle
			(at -1.27 3.81 90)
			(size 0.635 0.635)
			(layers "F.Cu" "F.Mask" "F.Paste")
			(net "P12V_STBY")
		)
		(pad "B5" smd circle
			(at -1.27 5.08 90)
			(size 0.635 0.635)
			(layers "F.Cu" "F.Mask" "F.Paste")
			(net "P12V_STBY")
		)
		(pad "B6" smd circle
			(at -1.27 6.35 90)
			(size 0.635 0.635)
			(layers "F.Cu" "F.Mask" "F.Paste")
			(net "P12V_STBY")
		)
		(pad "B7" smd circle
			(at -1.27 7.62 90)
			(size 0.635 0.635)
			(layers "F.Cu" "F.Mask" "F.Paste")
			(net "P12V_STBY")
		)
		(pad "B8" smd circle
			(at -1.27 8.89 90)
			(size 0.635 0.635)
			(layers "F.Cu" "F.Mask" "F.Paste")
			(net "P12V_STBY")
		)
		(pad "B9" smd circle
			(at -1.27 10.16 90)
			(size 0.635 0.635)
			(layers "F.Cu" "F.Mask" "F.Paste")
			(net "GND")
		)
		(pad "B10" smd circle
			(at -1.27 11.43 90)
			(size 0.635 0.635)
			(layers "F.Cu" "F.Mask" "F.Paste")
			(net "GND")
		)
		(pad "B11" smd circle
			(at -1.27 12.7 90)
			(size 0.635 0.635)
			(layers "F.Cu" "F.Mask" "F.Paste")
			(net "P3V3_STBY")
		)
		(pad "B12" smd circle
			(at -1.27 13.97 90)
			(size 0.635 0.635)
			(layers "F.Cu" "F.Mask" "F.Paste")
			(net "GND")
		)
		(pad "B13" smd circle
			(at -1.27 15.24 90)
			(size 0.635 0.635)
			(layers "F.Cu" "F.Mask" "F.Paste")
			(net "P5V_STBY")
		)
		(pad "B14" smd circle
			(at -1.27 16.51 90)
			(size 0.635 0.635)
			(layers "F.Cu" "F.Mask" "F.Paste")
			(net "GND")
		)
		(pad "B15" smd circle
			(at -1.27 17.78 90)
			(size 0.635 0.635)
			(layers "F.Cu" "F.Mask" "F.Paste")
			(net "PWRGD_P1V8MCP_CPU0")
		)
		(pad "B16" smd circle
			(at -1.27 19.05 90)
			(size 0.635 0.635)
			(layers "F.Cu" "F.Mask" "F.Paste")
			(net "PWRGD_PVCCIOMCP_CPU0")
		)
		(pad "B17" smd circle
			(at -1.27 20.32 90)
			(size 0.635 0.635)
			(layers "F.Cu" "F.Mask" "F.Paste")
			(net "GND")
		)
		(pad "B18" smd circle
			(at -1.27 21.59 90)
			(size 0.635 0.635)
			(layers "F.Cu" "F.Mask" "F.Paste")
			(net "SMB_VR_STBY_LVC3_SDA")
		)
		(pad "B19" smd circle
			(at -1.27 22.86 90)
			(size 0.635 0.635)
			(layers "F.Cu" "F.Mask" "F.Paste")
			(net "SVID_ALERT1_CPU0_R_N")
		)
		(pad "B20" smd circle
			(at -1.27 24.13 90)
			(size 0.635 0.635)
			(layers "F.Cu" "F.Mask" "F.Paste")
			(net "SVID_DIO0_CPU0_R")
		)
		(pad "C1" smd circle
			(at -2.54 0 90)
			(size 0.635 0.635)
			(layers "F.Cu" "F.Mask" "F.Paste")
			(net "GND")
		)
		(pad "C2" smd circle
			(at -2.54 1.27 90)
			(size 0.635 0.635)
			(layers "F.Cu" "F.Mask" "F.Paste")
			(net "GND")
		)
		(pad "C3" smd circle
			(at -2.54 2.54 90)
			(size 0.635 0.635)
			(layers "F.Cu" "F.Mask" "F.Paste")
			(net "GND")
		)
		(pad "C4" smd circle
			(at -2.54 3.81 90)
			(size 0.635 0.635)
			(layers "F.Cu" "F.Mask" "F.Paste")
			(net "GND")
		)
		(pad "C5" smd circle
			(at -2.54 5.08 90)
			(size 0.635 0.635)
			(layers "F.Cu" "F.Mask" "F.Paste")
			(net "GND")
		)
		(pad "C6" smd circle
			(at -2.54 6.35 90)
			(size 0.635 0.635)
			(layers "F.Cu" "F.Mask" "F.Paste")
			(net "GND")
		)
		(pad "C7" smd circle
			(at -2.54 7.62 90)
			(size 0.635 0.635)
			(layers "F.Cu" "F.Mask" "F.Paste")
			(net "GND")
		)
		(pad "C8" smd circle
			(at -2.54 8.89 90)
			(size 0.635 0.635)
			(layers "F.Cu" "F.Mask" "F.Paste")
			(net "GND")
		)
		(pad "C9" smd circle
			(at -2.54 10.16 90)
			(size 0.635 0.635)
			(layers "F.Cu" "F.Mask" "F.Paste")
			(net "GND")
		)
	)
)
